(kicad_pcb
	(version 20241229)
	(generator "pcbnew")
	(generator_version "9.0")
	(general
		(thickness 1.711)
		(legacy_teardrops no)
	)
	(paper "A4")
	(title_block
		(title "Antmicro Baseboard for Jetson AGX Thor")
		(date "2026-02-18")
		(rev "1.1.0")
		(company "Antmicro Ltd")
		(comment 1 "www.antmicro.com")
		(comment 9 "footprints 351-355 of 1170")
	)
	(layers
		(0 "F.Cu" signal)
		(4 "In1.Cu" signal)
		(6 "In2.Cu" signal)
		(8 "In3.Cu" signal)
		(10 "In4.Cu" jumper)
		(12 "In5.Cu" signal)
		(14 "In6.Cu" signal)
		(16 "In7.Cu" signal)
		(18 "In8.Cu" signal)
		(2 "B.Cu" signal)
		(9 "F.Adhes" user "F.Adhesive")
		(11 "B.Adhes" user "B.Adhesive")
		(13 "F.Paste" user)
		(15 "B.Paste" user)
		(5 "F.SilkS" user "F.Silkscreen")
		(7 "B.SilkS" user "B.Silkscreen")
		(1 "F.Mask" user)
		(3 "B.Mask" user)
		(17 "Dwgs.User" user "User.Drawings")
		(19 "Cmts.User" user "User.Comments")
		(21 "Eco1.User" user "User.Eco1")
		(23 "Eco2.User" user "User.Eco2")
		(25 "Edge.Cuts" user)
		(27 "Margin" user)
		(31 "F.CrtYd" user "F.Courtyard")
		(29 "B.CrtYd" user "B.Courtyard")
		(35 "F.Fab" user)
		(33 "B.Fab" user)
	)
	(footprint "antmicro-footprints:C_0805_2012Metric"
		(layer "F.Cu")
		(at 165.91 79.81 90)
		(descr "Capacitor SMD 0805")
		(tags "capacitor SMD 0805")
		(property "Reference" "C291"
			(at -4.59 0.39 90)
			(layer "F.SilkS")
			(effects
				(font
					(size 0.7 0.7)
					(thickness 0.15)
				)
				(justify left bottom)
			)
		)
		(property "Value" "C_22u_25V_0805"
			(at -2.055717 1.963152 90)
			(layer "F.Fab")
			(effects
				(font
					(size 0.7 0.7)
					(thickness 0.15)
				)
				(justify left bottom)
			)
		)
		(property "Datasheet" "https://product.samsungsem.com/mlcc/CL21A226MAYNNN.do"
			(at 0 0 90)
			(layer "F.Fab")
			(hide yes)
			(effects
				(font
					(size 1.27 1.27)
					(thickness 0.15)
				)
			)
		)
		(property "Description" "SMT Multilayer Ceramic Capacitor, 22uF, +/-20%, 25V, X5R, 0805 [2012 Metric]"
			(at 0 0 90)
			(layer "F.Fab")
			(hide yes)
			(effects
				(font
					(size 1.27 1.27)
					(thickness 0.15)
				)
			)
		)
		(property "MPN" "CL21A226MAYNNNE"
			(at 0 0 90)
			(unlocked yes)
			(layer "F.Fab")
			(hide yes)
			(effects
				(font
					(size 1 1)
					(thickness 0.15)
				)
			)
		)
		(property "Manufacturer" "Samsung Electro-Mechanics"
			(at 0 0 90)
			(unlocked yes)
			(layer "F.Fab")
			(hide yes)
			(effects
				(font
					(size 1 1)
					(thickness 0.15)
				)
			)
		)
		(property "License" "Apache-2.0"
			(at 0 0 90)
			(unlocked yes)
			(layer "F.Fab")
			(hide yes)
			(effects
				(font
					(size 1 1)
					(thickness 0.15)
				)
			)
		)
		(property "Author" "Antmicro"
			(at 0 0 90)
			(unlocked yes)
			(layer "F.Fab")
			(hide yes)
			(effects
				(font
					(size 1 1)
					(thickness 0.15)
				)
			)
		)
		(property "Val" "22u"
			(at 0 0 90)
			(unlocked yes)
			(layer "F.Fab")
			(hide yes)
			(effects
				(font
					(size 1 1)
					(thickness 0.15)
				)
			)
		)
		(property "Voltage" "25V"
			(at 0 0 90)
			(unlocked yes)
			(layer "F.Fab")
			(hide yes)
			(effects
				(font
					(size 1 1)
					(thickness 0.15)
				)
			)
		)
		(property "Dielectric" "X5R"
			(at 0 0 90)
			(unlocked yes)
			(layer "F.Fab")
			(hide yes)
			(effects
				(font
					(size 1 1)
					(thickness 0.15)
				)
			)
		)
		(property "Public" "False"
			(at 0 0 90)
			(unlocked yes)
			(layer "F.Fab")
			(hide yes)
			(effects
				(font
					(size 1 1)
					(thickness 0.15)
				)
			)
		)
		(component_classes
			(class "DCDC_20V")
		)
		(sheetname "/DCDC/")
		(sheetfile "dcdc.kicad_sch")
		(attr smd)
		(fp_line
			(start -0.3 -0.7)
			(end 0.3 -0.7)
			(stroke
				(width 0.15)
				(type solid)
			)
			(layer "F.SilkS")
		)
		(fp_line
			(start -0.3 0.7)
			(end 0.3 0.7)
			(stroke
				(width 0.15)
				(type solid)
			)
			(layer "F.SilkS")
		)
		(fp_rect
			(start 1.95 -0.9)
			(end -1.95 0.9)
			(stroke
				(width 0.05)
				(type default)
			)
			(fill no)
			(layer "F.CrtYd")
		)
		(fp_rect
			(start -0.95 -0.675)
			(end 0.95 0.675)
			(stroke
				(width 0.15)
				(type solid)
			)
			(fill no)
			(layer "F.Fab")
		)
		(fp_text user "License: Apache-2.0"
			(at -1.9 4.947 90)
			(layer "F.Fab")
			(effects
				(font
					(size 0.7 0.7)
					(thickness 0.15)
				)
				(justify left bottom)
			)
		)
		(fp_text user "Author: Antmicro"
			(at -1.9 5.947 90)
			(layer "F.Fab")
			(effects
				(font
					(size 0.7 0.7)
					(thickness 0.15)
				)
				(justify left bottom)
			)
		)
		(fp_text user "${REFERENCE}"
			(at -1.9 3.947 90)
			(layer "F.Fab")
			(effects
				(font
					(size 0.7 0.7)
					(thickness 0.15)
				)
				(justify left bottom)
			)
		)
		(pad "1" smd roundrect
			(at -1.1 0 90)
			(size 1.2 1.3)
			(layers "F.Cu" "F.Mask" "F.Paste")
			(roundrect_rratio 0.25)
			(net 1 "GND")
			(pintype "passive")
		)
		(pad "2" smd roundrect
			(at 1.1 0 90)
			(size 1.2 1.3)
			(layers "F.Cu" "F.Mask" "F.Paste")
			(roundrect_rratio 0.25)
			(net 1105 "/DCDC/20V_OUT")
			(pintype "passive")
		)
	)
	(footprint "antmicro-footprints:C_0402_1005Metric"
		(layer "F.Cu")
		(at 213.6 127.2 180)
		(descr "Capacitor SMD 0402")
		(tags "capacitor SMD 0402")
		(property "Reference" "C88"
			(at 1.1 0.5 180)
			(layer "F.SilkS")
			(effects
				(font
					(size 0.7 0.7)
					(thickness 0.15)
				)
				(justify left bottom)
			)
		)
		(property "Value" "C_100n_0402"
			(at -1.022927 2.155213 180)
			(layer "F.Fab")
			(effects
				(font
					(size 0.7 0.7)
					(thickness 0.15)
				)
				(justify left bottom)
			)
		)
		(property "Datasheet" "https://www.murata.com/products/productdetail?partno=GRM155R61H104KE14%23"
			(at 0 0 180)
			(layer "F.Fab")
			(hide yes)
			(effects
				(font
					(size 1.27 1.27)
					(thickness 0.15)
				)
			)
		)
		(property "Description" "SMD Multilayer Ceramic Capacitor, 0.1 µF, 50 V, 0402 [1005 Metric], ± 10%, X5R, GRM Series"
			(at 0 0 180)
			(layer "F.Fab")
			(hide yes)
			(effects
				(font
					(size 1.27 1.27)
					(thickness 0.15)
				)
			)
		)
		(property "MPN" "GRM155R61H104KE14D"
			(at 0 0 180)
			(unlocked yes)
			(layer "F.Fab")
			(hide yes)
			(effects
				(font
					(size 1 1)
					(thickness 0.15)
				)
			)
		)
		(property "Val" "100n"
			(at 0 0 180)
			(unlocked yes)
			(layer "F.Fab")
			(hide yes)
			(effects
				(font
					(size 1 1)
					(thickness 0.15)
				)
			)
		)
		(property "Voltage" "50V"
			(at 0 0 180)
			(unlocked yes)
			(layer "F.Fab")
			(hide yes)
			(effects
				(font
					(size 1 1)
					(thickness 0.15)
				)
			)
		)
		(property "Dielectric" "X5R"
			(at 0 0 180)
			(unlocked yes)
			(layer "F.Fab")
			(hide yes)
			(effects
				(font
					(size 1 1)
					(thickness 0.15)
				)
			)
		)
		(property "Manufacturer" "Murata"
			(at 0 0 180)
			(unlocked yes)
			(layer "F.Fab")
			(hide yes)
			(effects
				(font
					(size 1 1)
					(thickness 0.15)
				)
			)
		)
		(property "License" "Apache-2.0"
			(at 0 0 180)
			(unlocked yes)
			(layer "F.Fab")
			(hide yes)
			(effects
				(font
					(size 1 1)
					(thickness 0.15)
				)
			)
		)
		(property "Author" "Antmicro"
			(at 0 0 180)
			(unlocked yes)
			(layer "F.Fab")
			(hide yes)
			(effects
				(font
					(size 1 1)
					(thickness 0.15)
				)
			)
		)
		(sheetname "/USB Hub/")
		(sheetfile "usb_hub.kicad_sch")
		(attr smd)
		(fp_poly
			(pts
				(xy -0.925 -0.47) (xy 0.925 -0.47) (xy 0.925 0.47) (xy -0.925 0.47)
			)
			(stroke
				(width 0.05)
				(type default)
			)
			(fill no)
			(layer "F.CrtYd")
		)
		(fp_line
			(start 0.504 0.248)
			(end -0.494 0.248)
			(stroke
				(width 0.15)
				(type solid)
			)
			(layer "F.Fab")
		)
		(fp_line
			(start 0.504 -0.25)
			(end 0.504 0.248)
			(stroke
				(width 0.15)
				(type solid)
			)
			(layer "F.Fab")
		)
		(fp_line
			(start -0.494 0.248)
			(end -0.494 -0.25)
			(stroke
				(width 0.15)
				(type solid)
			)
			(layer "F.Fab")
		)
		(fp_line
			(start -0.494 -0.25)
			(end 0.504 -0.25)
			(stroke
				(width 0.15)
				(type solid)
			)
			(layer "F.Fab")
		)
		(fp_text user "License: Apache-2.0"
			(at -0.939 5.799 180)
			(layer "F.Fab")
			(effects
				(font
					(size 0.7 0.7)
					(thickness 0.15)
				)
				(justify left bottom)
			)
		)
		(fp_text user "${REFERENCE}"
			(at -0.939 4.599 180)
			(layer "F.Fab")
			(effects
				(font
					(size 0.7 0.7)
					(thickness 0.15)
				)
				(justify left bottom)
			)
		)
		(fp_text user "Author: Antmicro"
			(at -0.939 3.399 180)
			(layer "F.Fab")
			(effects
				(font
					(size 0.7 0.7)
					(thickness 0.15)
				)
				(justify left bottom)
			)
		)
		(pad "1" smd roundrect
			(at -0.48 0 180)
			(size 0.59 0.64)
			(layers "F.Cu" "F.Mask" "F.Paste")
			(roundrect_rratio 0.25)
			(net 1 "GND")
			(pintype "passive")
		)
		(pad "2" smd roundrect
			(at 0.48 0 180)
			(size 0.59 0.64)
			(layers "F.Cu" "F.Mask" "F.Paste")
			(roundrect_rratio 0.25)
			(net 282 "+1V15")
			(pintype "passive")
		)
	)
	(footprint "antmicro-footprints:C_0603_1608Metric_EIA"
		(layer "F.Cu")
		(at 192.47 125.5 180)
		(descr "Capacitor SMD 0603, IPC-7351 Density Level A")
		(tags "Capacitor 0603")
		(property "Reference" "C224"
			(at -1.42757 -7.9 0)
			(layer "F.SilkS")
			(effects
				(font
					(size 0.7 0.7)
					(thickness 0.15)
				)
				(justify right top)
			)
		)
		(property "Value" "C_22u_16V_0603"
			(at -1.42757 1.770288 0)
			(layer "F.Fab")
			(effects
				(font
					(size 0.7 0.7)
					(thickness 0.15)
				)
				(justify right top)
			)
		)
		(property "Datasheet" "https://product.samsungsem.com/mlcc/CL10A226MO7JZN.do"
			(at 0 0 0)
			(layer "F.Fab")
			(hide yes)
			(effects
				(font
					(size 1.27 1.27)
					(thickness 0.15)
				)
			)
		)
		(property "Description" "SMD Multilayer Ceramic Capacitor"
			(at 0 0 0)
			(layer "F.Fab")
			(hide yes)
			(effects
				(font
					(size 1.27 1.27)
					(thickness 0.15)
				)
			)
		)
		(property "Val" "22u"
			(at 0 0 0)
			(unlocked yes)
			(layer "F.Fab")
			(hide yes)
			(effects
				(font
					(size 1 1)
					(thickness 0.15)
				)
			)
		)
		(property "MPN" "CL10A226MO7JZNC"
			(at 0 0 0)
			(unlocked yes)
			(layer "F.Fab")
			(hide yes)
			(effects
				(font
					(size 1 1)
					(thickness 0.15)
				)
			)
		)
		(property "Manufacturer" "Samsung Electro-Mechanics"
			(at 0 0 0)
			(unlocked yes)
			(layer "F.Fab")
			(hide yes)
			(effects
				(font
					(size 1 1)
					(thickness 0.15)
				)
			)
		)
		(property "License" "Apache-2.0"
			(at 0 0 0)
			(unlocked yes)
			(layer "F.Fab")
			(hide yes)
			(effects
				(font
					(size 1 1)
					(thickness 0.15)
				)
			)
		)
		(property "Author" "Antmicro"
			(at 0 0 0)
			(unlocked yes)
			(layer "F.Fab")
			(hide yes)
			(effects
				(font
					(size 1 1)
					(thickness 0.15)
				)
			)
		)
		(property "Voltage" "16V"
			(at 0 0 0)
			(unlocked yes)
			(layer "F.Fab")
			(hide yes)
			(effects
				(font
					(size 1 1)
					(thickness 0.15)
				)
			)
		)
		(property "Dielectric" ""
			(at 0 0 0)
			(unlocked yes)
			(layer "F.Fab")
			(hide yes)
			(effects
				(font
					(size 1 1)
					(thickness 0.15)
				)
			)
		)
		(component_classes
			(class "DCDC_1V15")
		)
		(sheetname "/DCDC/")
		(sheetfile "dcdc.kicad_sch")
		(attr smd)
		(fp_line
			(start -0.15 0.55)
			(end 0.15 0.55)
			(stroke
				(width 0.15)
				(type solid)
			)
			(layer "F.SilkS")
		)
		(fp_line
			(start -0.15 -0.55)
			(end 0.15 -0.55)
			(stroke
				(width 0.15)
				(type solid)
			)
			(layer "F.SilkS")
		)
		(fp_rect
			(start -1.25 -0.65)
			(end 1.25 0.65)
			(stroke
				(width 0.05)
				(type solid)
			)
			(fill no)
			(layer "F.CrtYd")
		)
		(fp_rect
			(start -0.8 -0.45)
			(end 0.8 0.45)
			(stroke
				(width 0.15)
				(type solid)
			)
			(fill no)
			(layer "F.Fab")
		)
		(fp_text user "${REFERENCE}"
			(at -1.682 3.895 0)
			(layer "F.Fab")
			(effects
				(font
					(size 0.7 0.7)
					(thickness 0.15)
				)
				(justify right top)
			)
		)
		(fp_text user "Author: Antmicro"
			(at -1.682 4.894 0)
			(layer "F.Fab")
			(effects
				(font
					(size 0.7 0.7)
					(thickness 0.15)
				)
				(justify right top)
			)
		)
		(fp_text user "License: Apache-2.0"
			(at -1.682 5.895 0)
			(layer "F.Fab")
			(effects
				(font
					(size 0.7 0.7)
					(thickness 0.15)
				)
				(justify right top)
			)
		)
		(pad "1" smd roundrect
			(at -0.7 0 180)
			(size 0.8 1.1)
			(layers "F.Cu" "F.Mask" "F.Paste")
			(roundrect_rratio 0.2)
			(net 280 "/DCDC/1V15_OUT")
			(pintype "passive")
		)
		(pad "2" smd roundrect
			(at 0.7 0 180)
			(size 0.8 1.1)
			(layers "F.Cu" "F.Mask" "F.Paste")
			(roundrect_rratio 0.2)
			(net 1 "GND")
			(pintype "passive")
		)
	)
	(footprint "antmicro-footprints:R_0402_1005Metric"
		(layer "F.Cu")
		(at 182.933525 123.947019)
		(descr "Resistor SMD 0402")
		(tags "resistor SMD 0402")
		(property "Reference" "R55"
			(at -0.333525 -1.347019 0)
			(layer "F.SilkS")
			(effects
				(font
					(size 0.7 0.7)
					(thickness 0.15)
				)
				(justify left bottom)
			)
		)
		(property "Value" "R_10k_0402"
			(at -1.011843 1.772047 0)
			(layer "F.Fab")
			(effects
				(font
					(size 0.7 0.7)
					(thickness 0.15)
				)
				(justify left bottom)
			)
		)
		(property "Datasheet" "https://www.bourns.com/docs/product-datasheets/cr.pdf"
			(at 0 0 0)
			(layer "F.Fab")
			(hide yes)
			(effects
				(font
					(size 1.27 1.27)
					(thickness 0.15)
				)
			)
		)
		(property "Description" "SMD Chip Resistor, 10 kohm, ± 1%, 62.5 mW, 0402 [1005 Metric], Thick Film, General Purpose"
			(at 0 0 0)
			(layer "F.Fab")
			(hide yes)
			(effects
				(font
					(size 1.27 1.27)
					(thickness 0.15)
				)
			)
		)
		(property "MPN" "CR0402-FX-1002GLF"
			(at 0 0 0)
			(unlocked yes)
			(layer "F.Fab")
			(hide yes)
			(effects
				(font
					(size 1 1)
					(thickness 0.15)
				)
			)
		)
		(property "Manufacturer" "Bourns"
			(at 0 0 0)
			(unlocked yes)
			(layer "F.Fab")
			(hide yes)
			(effects
				(font
					(size 1 1)
					(thickness 0.15)
				)
			)
		)
		(property "License" "Apache-2.0"
			(at 0 0 0)
			(unlocked yes)
			(layer "F.Fab")
			(hide yes)
			(effects
				(font
					(size 1 1)
					(thickness 0.15)
				)
			)
		)
		(property "Author" "Antmicro"
			(at 0 0 0)
			(unlocked yes)
			(layer "F.Fab")
			(hide yes)
			(effects
				(font
					(size 1 1)
					(thickness 0.15)
				)
			)
		)
		(property "Val" "10k"
			(at 0 0 0)
			(unlocked yes)
			(layer "F.Fab")
			(hide yes)
			(effects
				(font
					(size 1 1)
					(thickness 0.15)
				)
			)
		)
		(property "Tolerance" "1%"
			(at 0 0 0)
			(unlocked yes)
			(layer "F.Fab")
			(hide yes)
			(effects
				(font
					(size 1 1)
					(thickness 0.15)
				)
			)
		)
		(sheetname "/DCDC/")
		(sheetfile "dcdc.kicad_sch")
		(attr smd)
		(fp_rect
			(start -0.925 -0.47)
			(end 0.925 0.47)
			(stroke
				(width 0.05)
				(type default)
			)
			(fill no)
			(layer "F.CrtYd")
		)
		(fp_rect
			(start -0.5 -0.25)
			(end 0.5 0.25)
			(stroke
				(width 0.15)
				(type solid)
			)
			(fill no)
			(layer "F.Fab")
		)
		(fp_text user "License: Apache-2.0"
			(at -0.95 5.169 0)
			(layer "F.Fab")
			(effects
				(font
					(size 0.7 0.7)
					(thickness 0.15)
				)
				(justify left bottom)
			)
		)
		(fp_text user "${REFERENCE}"
			(at -0.95 3.168 0)
			(layer "F.Fab")
			(effects
				(font
					(size 0.7 0.7)
					(thickness 0.15)
				)
				(justify left bottom)
			)
		)
		(fp_text user "Author: Antmicro"
			(at -0.95 4.169 0)
			(layer "F.Fab")
			(effects
				(font
					(size 0.7 0.7)
					(thickness 0.15)
				)
				(justify left bottom)
			)
		)
		(pad "1" smd roundrect
			(at -0.48 0)
			(size 0.59 0.64)
			(layers "F.Cu" "F.Mask" "F.Paste")
			(roundrect_rratio 0.25)
			(net 1 "GND")
			(pintype "passive")
		)
		(pad "2" smd roundrect
			(at 0.48 0)
			(size 0.59 0.64)
			(layers "F.Cu" "F.Mask" "F.Paste")
			(roundrect_rratio 0.25)
			(net 1218 "/DCDC/3V3_FB")
			(pintype "passive")
		)
	)
	(footprint "antmicro-footprints:R_0402_1005Metric"
		(layer "F.Cu")
		(at 130.549999 62.97 180)
		(descr "Resistor SMD 0402")
		(tags "resistor SMD 0402")
		(property "Reference" "R312"
			(at 0.929999 -2.36 0)
			(layer "F.SilkS")
			(effects
				(font
					(size 0.7 0.7)
					(thickness 0.15)
				)
				(justify left bottom)
			)
		)
		(property "Value" "R_73k2_0402"
			(at -1.011843 1.772046 0)
			(layer "F.Fab")
			(effects
				(font
					(size 0.7 0.7)
					(thickness 0.15)
				)
				(justify right top)
			)
		)
		(property "Datasheet" "https://www.bourns.com/docs/product-datasheets/cr.pdf"
			(at 0 0 0)
			(layer "F.Fab")
			(hide yes)
			(effects
				(font
					(size 1.27 1.27)
					(thickness 0.15)
				)
			)
		)
		(property "Description" "SMD Chip Resistor"
			(at 0 0 0)
			(layer "F.Fab")
			(hide yes)
			(effects
				(font
					(size 1.27 1.27)
					(thickness 0.15)
				)
			)
		)
		(property "MPN" "CR0402-FX-7322GLF"
			(at 0 0 180)
			(unlocked yes)
			(layer "F.Fab")
			(hide yes)
			(effects
				(font
					(size 1 1)
					(thickness 0.15)
				)
			)
		)
		(property "Manufacturer" "Bourns"
			(at 0 0 180)
			(unlocked yes)
			(layer "F.Fab")
			(hide yes)
			(effects
				(font
					(size 1 1)
					(thickness 0.15)
				)
			)
		)
		(property "License" "Apache-2.0"
			(at 0 0 180)
			(unlocked yes)
			(layer "F.Fab")
			(hide yes)
			(effects
				(font
					(size 1 1)
					(thickness 0.15)
				)
			)
		)
		(property "Author" "Antmicro"
			(at 0 0 180)
			(unlocked yes)
			(layer "F.Fab")
			(hide yes)
			(effects
				(font
					(size 1 1)
					(thickness 0.15)
				)
			)
		)
		(property "Val" "73k2"
			(at 0 0 180)
			(unlocked yes)
			(layer "F.Fab")
			(hide yes)
			(effects
				(font
					(size 1 1)
					(thickness 0.15)
				)
			)
		)
		(property "Tolerance" "1%"
			(at 0 0 180)
			(unlocked yes)
			(layer "F.Fab")
			(hide yes)
			(effects
				(font
					(size 1 1)
					(thickness 0.15)
				)
			)
		)
		(sheetname "/DCDC/")
		(sheetfile "dcdc.kicad_sch")
		(attr smd)
		(fp_poly
			(pts
				(xy -0.925 -0.47) (xy 0.925 -0.47) (xy 0.925 0.47) (xy -0.925 0.47)
			)
			(stroke
				(width 0.05)
				(type default)
			)
			(fill no)
			(layer "F.CrtYd")
		)
		(fp_poly
			(pts
				(xy -0.5 -0.25) (xy 0.5 -0.25) (xy 0.5 0.25) (xy -0.5 0.25)
			)
			(stroke
				(width 0.15)
				(type solid)
			)
			(fill no)
			(layer "F.Fab")
		)
		(fp_text user "License: Apache-2.0"
			(at -0.949999 5.169 0)
			(layer "F.Fab")
			(effects
				(font
					(size 0.7 0.7)
					(thickness 0.15)
				)
				(justify right top)
			)
		)
		(fp_text user "Author: Antmicro"
			(at -0.95 4.169 0)
			(layer "F.Fab")
			(effects
				(font
					(size 0.7 0.7)
					(thickness 0.15)
				)
				(justify right top)
			)
		)
		(fp_text user "${REFERENCE}"
			(at -0.95 3.168 0)
			(layer "F.Fab")
			(effects
				(font
					(size 0.7 0.7)
					(thickness 0.15)
				)
				(justify right top)
			)
		)
		(pad "1" smd roundrect
			(at -0.48 0 180)
			(size 0.59 0.64)
			(layers "F.Cu" "F.Mask" "F.Paste")
			(roundrect_rratio 0.25)
			(net 1308 "/DCDC/5V_{AON}_FB")
			(pintype "passive")
		)
		(pad "2" smd roundrect
			(at 0.48 0 180)
			(size 0.59 0.64)
			(layers "F.Cu" "F.Mask" "F.Paste")
			(roundrect_rratio 0.25)
			(net 1278 "/DCDC/5V_{AON}_OUT")
			(pintype "passive")
		)
	)
)
